(kicad_pcb
	(version 20260206)
	(generator "pcbnew")
	(generator_version "10.0")
	(general
		(thickness 1.6)
		(legacy_teardrops no)
	)
	(paper "A4")
	(title_block
		(title "Wiwynn_Tioga_Pass_MB.brd")
		(comment 1 "Tioga Pass / footprints 2191-2197 of 4770")
	)
	(layers
		(0 "F.Cu" signal "TOP")
		(4 "In1.Cu" signal "L2GND")
		(6 "In2.Cu" signal "L3")
		(8 "In3.Cu" signal "L4GND")
		(10 "In4.Cu" signal "L5")
		(12 "In5.Cu" signal "L6GND")
		(14 "In6.Cu" signal "L7VCC")
		(16 "In7.Cu" signal "L8VCC")
		(18 "In8.Cu" signal "L9GND")
		(20 "In9.Cu" signal "L10")
		(22 "In10.Cu" signal "L11GND")
		(24 "In11.Cu" signal "L12")
		(26 "In12.Cu" signal "L13GND")
		(2 "B.Cu" signal "BOTTOM")
		(9 "F.Adhes" user "F.Adhesive")
		(11 "B.Adhes" user "B.Adhesive")
		(13 "F.Paste" user "Package Geometry/Pastemask Top")
		(15 "B.Paste" user "Package Geometry/Pastemask Bottom")
		(5 "F.SilkS" user "Ref Des/Silkscreen Top")
		(7 "B.SilkS" user "Ref Des/Silkscreen Bottom")
		(1 "F.Mask" user "Board Geometry/Soldermask Top")
		(3 "B.Mask" user "Board Geometry/Soldermask Bottom")
		(17 "Dwgs.User" user "User.Drawings")
		(19 "Cmts.User" user "User.Comments")
		(21 "Eco1.User" user "User.Eco1")
		(23 "Eco2.User" user "User.Eco2")
		(25 "Edge.Cuts" user "Board Geometry/Outline")
		(27 "Margin" user)
		(31 "F.CrtYd" user "Package Geometry/Place Bound Top")
		(29 "B.CrtYd" user "Package Geometry/Place Bound Bottom")
		(35 "F.Fab" user "Ref Des/Assembly Top")
		(33 "B.Fab" user "Ref Des/Assembly Bottom")
	)
	(footprint ""
		(layer "F.Cu")
		(at 332.90002 -118.5164 -90)
		(property "Reference" "C842"
			(at -0.8382 -0.67818 270)
			(unlocked yes)
			(layer "F.SilkS")
			(effects
				(font
					(size 0.4064 0.254)
					(thickness 0.1524)
				)
				(justify left)
			)
		)
		(property "Value" ""
			(at 0 0 270)
			(layer "F.Fab")
			(effects
				(font
					(size 1.27 1.27)
				)
			)
		)
		(duplicate_pad_numbers_are_jumpers no)
		(fp_poly
			(pts
				(xy 0.3048 -0.1016) (xy 0.3048 0.9906) (xy -0.3048 0.9906) (xy -0.3048 -0.1016)
			)
			(stroke
				(width 0)
				(type default)
			)
			(fill no)
			(layer "F.CrtYd")
		)
		(fp_line
			(start -0.3048 0.9906)
			(end 0.3048 0.9906)
			(stroke
				(width 0.1)
				(type default)
			)
			(layer "F.Fab")
		)
		(fp_line
			(start 0.3048 0.9906)
			(end 0.3048 -0.1016)
			(stroke
				(width 0.1)
				(type default)
			)
			(layer "F.Fab")
		)
		(fp_line
			(start -0.3048 -0.1016)
			(end -0.3048 0.9906)
			(stroke
				(width 0.1)
				(type default)
			)
			(layer "F.Fab")
		)
		(fp_line
			(start 0.3048 -0.1016)
			(end -0.3048 -0.1016)
			(stroke
				(width 0.1)
				(type default)
			)
			(layer "F.Fab")
		)
		(pad "1" smd rect
			(at 0 0 270)
			(size 0.508 0.508)
			(layers "F.Cu" "F.Mask" "F.Paste")
			(net "P3E_CPU0_PE1_PCH_TXN<8>")
		)
		(pad "2" smd rect
			(at 0 0.889 270)
			(size 0.508 0.508)
			(layers "F.Cu" "F.Mask" "F.Paste")
			(net "P3E_CPU0_PE1_PCH_CON_TXN<8>")
		)
		(zone
			(layer "F.Cu")
			(hatch none 0.5)
			(connect_pads
				(clearance 0)
			)
			(min_thickness 0.25)
			(keepout
				(tracks not_allowed)
				(vias allowed)
				(pads allowed)
				(copperpour not_allowed)
				(footprints allowed)
			)
			(placement
				(enabled no)
				(sheetname "")
			)
			(fill
				(thermal_gap 0.5)
				(thermal_bridge_width 0.5)
				(island_removal_mode 0)
			)
			(polygon
				(pts
					(xy 332.26502 -118.7704) (xy 332.26502 -118.2624) (xy 332.64602 -118.2624) (xy 332.64602 -118.7704)
				)
			)
		)
		(zone
			(layer "F.Cu")
			(hatch none 0.5)
			(connect_pads
				(clearance 0)
			)
			(min_thickness 0.25)
			(keepout
				(tracks allowed)
				(vias not_allowed)
				(pads allowed)
				(copperpour not_allowed)
				(footprints allowed)
			)
			(placement
				(enabled no)
				(sheetname "")
			)
			(fill
				(thermal_gap 0.5)
				(thermal_bridge_width 0.5)
				(island_removal_mode 0)
			)
			(polygon
				(pts
					(xy 332.64602 -118.7704) (xy 332.64602 -118.2624) (xy 332.26502 -118.2624) (xy 332.26502 -118.7704)
				)
			)
		)
	)
	(footprint ""
		(layer "F.Cu")
		(at 23.697184 -97.562416 180)
		(property "Reference" "RF12"
			(at -0.8382 -0.67818 180)
			(unlocked yes)
			(layer "F.SilkS")
			(effects
				(font
					(size 0.4064 0.254)
					(thickness 0.1524)
				)
				(justify left)
			)
		)
		(property "Value" ""
			(at 0 0 180)
			(layer "F.Fab")
			(effects
				(font
					(size 1.27 1.27)
				)
			)
		)
		(duplicate_pad_numbers_are_jumpers no)
		(fp_poly
			(pts
				(xy -0.2794 -0.1016) (xy 0.2794 -0.1016) (xy 0.2794 0.9906) (xy -0.2794 0.9906)
			)
			(stroke
				(width 0)
				(type default)
			)
			(fill no)
			(layer "F.CrtYd")
		)
		(fp_line
			(start 0.2794 0.9906)
			(end 0.2794 -0.1016)
			(stroke
				(width 0.1)
				(type default)
			)
			(layer "F.Fab")
		)
		(fp_line
			(start 0.2794 -0.1016)
			(end -0.2794 -0.1016)
			(stroke
				(width 0.1)
				(type default)
			)
			(layer "F.Fab")
		)
		(fp_line
			(start -0.2794 0.9906)
			(end 0.2794 0.9906)
			(stroke
				(width 0.1)
				(type default)
			)
			(layer "F.Fab")
		)
		(fp_line
			(start -0.2794 -0.1016)
			(end -0.2794 0.9906)
			(stroke
				(width 0.1)
				(type default)
			)
			(layer "F.Fab")
		)
		(pad "1" smd rect
			(at 0 0 180)
			(size 0.508 0.508)
			(layers "F.Cu" "F.Mask" "F.Paste")
			(net "VR_PVSA_CPU1_BIREF1")
		)
		(pad "2" smd rect
			(at 0 0.889 180)
			(size 0.508 0.508)
			(layers "F.Cu" "F.Mask" "F.Paste")
			(net "ISENSE_PVSA_CPU1_IMON")
		)
		(zone
			(layer "F.Cu")
			(hatch none 0.5)
			(connect_pads
				(clearance 0)
			)
			(min_thickness 0.25)
			(keepout
				(tracks not_allowed)
				(vias allowed)
				(pads allowed)
				(copperpour not_allowed)
				(footprints allowed)
			)
			(placement
				(enabled no)
				(sheetname "")
			)
			(fill
				(thermal_gap 0.5)
				(thermal_bridge_width 0.5)
				(island_removal_mode 0)
			)
			(polygon
				(pts
					(xy 23.951184 -98.197416) (xy 23.443184 -98.197416) (xy 23.443184 -97.816416) (xy 23.951184 -97.816416)
				)
			)
		)
		(zone
			(layer "F.Cu")
			(hatch none 0.5)
			(connect_pads
				(clearance 0)
			)
			(min_thickness 0.25)
			(keepout
				(tracks allowed)
				(vias not_allowed)
				(pads allowed)
				(copperpour not_allowed)
				(footprints allowed)
			)
			(placement
				(enabled no)
				(sheetname "")
			)
			(fill
				(thermal_gap 0.5)
				(thermal_bridge_width 0.5)
				(island_removal_mode 0)
			)
			(polygon
				(pts
					(xy 23.951184 -97.816416) (xy 23.443184 -97.816416) (xy 23.443184 -98.197416) (xy 23.951184 -98.197416)
				)
			)
		)
	)
	(footprint ""
		(layer "F.Cu")
		(at 201.422 -85.4456 -90)
		(property "Reference" "RT24"
			(at 0 0 270)
			(layer "F.SilkS")
			(hide yes)
			(effects
				(font
					(size 1.27 1.27)
				)
			)
		)
		(property "Value" "*"
			(at -0.0254 -2.6289 270)
			(unlocked yes)
			(layer "F.Fab")
			(hide yes)
			(effects
				(font
					(size 1.27 1.016)
					(thickness 0.1524)
				)
			)
		)
		(property "Device Type" "1R3F-GP_RCL_GP-1R3F-GP,64.1R00A"
			(at -0.0254 -4.1529 270)
			(unlocked yes)
			(layer "F.Fab")
			(hide yes)
			(effects
				(font
					(size 1.27 1.016)
					(thickness 0.1524)
				)
			)
		)
		(duplicate_pad_numbers_are_jumpers no)
		(fp_line
			(start -0.4826 0)
			(end -0.2032 0)
			(stroke
				(width 0.2032)
				(type default)
			)
			(layer "F.SilkS")
		)
		(fp_line
			(start 0.2032 0)
			(end 0.4826 0)
			(stroke
				(width 0.2032)
				(type default)
			)
			(layer "F.SilkS")
		)
		(fp_rect
			(start -0.5842 1.3335)
			(end 0.5842 -1.3335)
			(stroke
				(width 0)
				(type default)
			)
			(fill no)
			(layer "F.CrtYd")
		)
		(fp_rect
			(start -0.5842 1.3335)
			(end 0.5842 -1.3335)
			(stroke
				(width 0)
				(type default)
			)
			(fill no)
			(layer "F.Fab")
		)
		(pad "1" smd custom
			(at 0 -0.762 270)
			(size 0.2159 0.2159)
			(layers "F.Cu" "F.Mask" "F.Paste")
			(net "VR_PVCCIN_CPU0_PHASE5_RC")
			(options
				(clearance outline)
				(anchor circle)
			)
			(primitives
				(gr_poly
					(pts
						(arc
							(start -0.3302 -0.4318)
							(mid -0.402042 -0.402042)
							(end -0.4318 -0.3302)
						)
						(arc
							(start -0.4318 0.3302)
							(mid -0.402042 0.402042)
							(end -0.3302 0.4318)
						)
						(arc
							(start 0.3302 0.4318)
							(mid 0.402042 0.402042)
							(end 0.4318 0.3302)
						)
						(arc
							(start 0.4318 -0.3302)
							(mid 0.402042 -0.402042)
							(end 0.3302 -0.4318)
						)
					)
					(width 0)
					(fill yes)
				)
			)
		)
		(pad "2" smd custom
			(at 0 0.762 270)
			(size 0.2159 0.2159)
			(layers "F.Cu" "F.Mask" "F.Paste")
			(net "GND")
			(options
				(clearance outline)
				(anchor circle)
			)
			(primitives
				(gr_poly
					(pts
						(arc
							(start -0.3302 -0.4318)
							(mid -0.402042 -0.402042)
							(end -0.4318 -0.3302)
						)
						(arc
							(start -0.4318 0.3302)
							(mid -0.402042 0.402042)
							(end -0.3302 0.4318)
						)
						(arc
							(start 0.3302 0.4318)
							(mid 0.402042 0.402042)
							(end 0.4318 0.3302)
						)
						(arc
							(start 0.4318 -0.3302)
							(mid 0.402042 -0.402042)
							(end 0.3302 -0.4318)
						)
					)
					(width 0)
					(fill yes)
				)
			)
		)
	)
	(footprint ""
		(layer "F.Cu")
		(at 339.3948 -103.9368 90)
		(property "Reference" "C7C6"
			(at 0 0 90)
			(layer "F.SilkS")
			(hide yes)
			(effects
				(font
					(size 1.27 1.27)
				)
			)
		)
		(property "Value" ""
			(at 0 0 90)
			(layer "F.Fab")
			(effects
				(font
					(size 1.27 1.27)
				)
			)
		)
		(duplicate_pad_numbers_are_jumpers no)
		(fp_poly
			(pts
				(xy -0.4953 -0.2032) (xy 0.4953 -0.2032) (xy 0.4953 1.6002) (xy -0.4953 1.6002)
			)
			(stroke
				(width 0)
				(type default)
			)
			(fill no)
			(layer "F.CrtYd")
		)
		(fp_line
			(start 0.4953 -0.2032)
			(end 0.4953 1.6002)
			(stroke
				(width 0.1)
				(type default)
			)
			(layer "F.Fab")
		)
		(fp_line
			(start -0.4953 -0.2032)
			(end 0.4953 -0.2032)
			(stroke
				(width 0.1)
				(type default)
			)
			(layer "F.Fab")
		)
		(fp_line
			(start 0.4953 1.6002)
			(end -0.4953 1.6002)
			(stroke
				(width 0.1)
				(type default)
			)
			(layer "F.Fab")
		)
		(fp_line
			(start -0.4953 1.6002)
			(end -0.4953 -0.2032)
			(stroke
				(width 0.1)
				(type default)
			)
			(layer "F.Fab")
		)
		(pad "1" smd rect
			(at 0 0 90)
			(size 0.762 0.889)
			(layers "F.Cu" "F.Mask" "F.Paste")
			(net "PVCCIO_CPU0")
		)
		(pad "2" smd rect
			(at 0 1.397 90)
			(size 0.762 0.889)
			(layers "F.Cu" "F.Mask" "F.Paste")
			(net "GND")
		)
		(zone
			(layer "F.Cu")
			(hatch none 0.5)
			(connect_pads
				(clearance 0)
			)
			(min_thickness 0.25)
			(keepout
				(tracks not_allowed)
				(vias allowed)
				(pads allowed)
				(copperpour not_allowed)
				(footprints allowed)
			)
			(placement
				(enabled no)
				(sheetname "")
			)
			(fill
				(thermal_gap 0.5)
				(thermal_bridge_width 0.5)
				(island_removal_mode 0)
			)
			(polygon
				(pts
					(xy 339.8393 -103.5558) (xy 339.8393 -104.3178) (xy 340.3473 -104.3178) (xy 340.3473 -103.5558)
				)
			)
		)
	)
	(footprint ""
		(layer "F.Cu")
		(at 13.8938 -25.019 90)
		(property "Reference" "C1F17"
			(at 0 0 90)
			(layer "F.SilkS")
			(hide yes)
			(effects
				(font
					(size 1.27 1.27)
				)
			)
		)
		(property "Value" ""
			(at 0 0 90)
			(layer "F.Fab")
			(effects
				(font
					(size 1.27 1.27)
				)
			)
		)
		(duplicate_pad_numbers_are_jumpers no)
		(fp_rect
			(start -0.3048 -0.1016)
			(end 0.3048 0.9906)
			(stroke
				(width 0)
				(type default)
			)
			(fill no)
			(layer "F.CrtYd")
		)
		(fp_line
			(start 0.3048 -0.1016)
			(end -0.3048 -0.1016)
			(stroke
				(width 0.1)
				(type default)
			)
			(layer "F.Fab")
		)
		(fp_line
			(start -0.3048 -0.1016)
			(end -0.3048 0.9906)
			(stroke
				(width 0.1)
				(type default)
			)
			(layer "F.Fab")
		)
		(fp_line
			(start 0.3048 0.9906)
			(end 0.3048 -0.1016)
			(stroke
				(width 0.1)
				(type default)
			)
			(layer "F.Fab")
		)
		(fp_line
			(start -0.3048 0.9906)
			(end 0.3048 0.9906)
			(stroke
				(width 0.1)
				(type default)
			)
			(layer "F.Fab")
		)
		(pad "1" smd rect
			(at 0 0 90)
			(size 0.508 0.508)
			(layers "F.Cu" "F.Mask" "F.Paste")
			(net "P3E_CPU1_PE3_MP_C_TXP<1>")
		)
		(pad "2" smd rect
			(at 0 0.889 90)
			(size 0.508 0.508)
			(layers "F.Cu" "F.Mask" "F.Paste")
			(net "P3E_CPU1_PE3_MP_TXP<1>")
		)
		(zone
			(layer "F.Cu")
			(hatch none 0.5)
			(connect_pads
				(clearance 0)
			)
			(min_thickness 0.25)
			(keepout
				(tracks allowed)
				(vias not_allowed)
				(pads allowed)
				(copperpour not_allowed)
				(footprints allowed)
			)
			(placement
				(enabled no)
				(sheetname "")
			)
			(fill
				(thermal_gap 0.5)
				(thermal_bridge_width 0.5)
				(island_removal_mode 0)
			)
			(polygon
				(pts
					(xy 14.1478 -24.765) (xy 14.5288 -24.765) (xy 14.5288 -25.273) (xy 14.1478 -25.273)
				)
			)
		)
		(zone
			(layer "F.Cu")
			(hatch none 0.5)
			(connect_pads
				(clearance 0)
			)
			(min_thickness 0.25)
			(keepout
				(tracks not_allowed)
				(vias allowed)
				(pads allowed)
				(copperpour not_allowed)
				(footprints allowed)
			)
			(placement
				(enabled no)
				(sheetname "")
			)
			(fill
				(thermal_gap 0.5)
				(thermal_bridge_width 0.5)
				(island_removal_mode 0)
			)
			(polygon
				(pts
					(xy 14.1478 -24.765) (xy 14.5288 -24.765) (xy 14.5288 -25.273) (xy 14.1478 -25.273)
				)
			)
		)
	)
	(footprint ""
		(layer "F.Cu")
		(at 101.3968 -149.8092 90)
		(property "Reference" "C2A6"
			(at 1.848866 0.752348 90)
			(unlocked yes)
			(layer "F.SilkS")
			(effects
				(font
					(size 1.27 0.9652)
					(thickness 0.1524)
				)
			)
		)
		(property "Value" ""
			(at 0 0 90)
			(layer "F.Fab")
			(effects
				(font
					(size 1.27 1.27)
				)
			)
		)
		(duplicate_pad_numbers_are_jumpers no)
		(fp_rect
			(start -0.500126 1.598422)
			(end 0.500126 -0.201422)
			(stroke
				(width 0)
				(type default)
			)
			(fill no)
			(layer "F.CrtYd")
		)
		(fp_line
			(start 0.500126 -0.201422)
			(end 0.500126 1.598422)
			(stroke
				(width 0.1)
				(type default)
			)
			(layer "F.Fab")
		)
		(fp_line
			(start -0.500126 -0.201422)
			(end 0.500126 -0.201422)
			(stroke
				(width 0.1)
				(type default)
			)
			(layer "F.Fab")
		)
		(fp_line
			(start 0.500126 1.598422)
			(end -0.500126 1.598422)
			(stroke
				(width 0.1)
				(type default)
			)
			(layer "F.Fab")
		)
		(fp_line
			(start -0.500126 1.598422)
			(end -0.500126 -0.201422)
			(stroke
				(width 0.1)
				(type default)
			)
			(layer "F.Fab")
		)
		(pad "1" smd rect
			(at 0 0)
			(size 0.889 0.9906)
			(layers "F.Cu" "F.Mask" "F.Paste")
			(net "PVDDQ_KLM")
		)
		(pad "2" smd rect
			(at 0 1.397)
			(size 0.889 0.9906)
			(layers "F.Cu" "F.Mask" "F.Paste")
			(net "GND")
		)
		(zone
			(layer "F.Cu")
			(hatch none 0.5)
			(connect_pads
				(clearance 0)
			)
			(min_thickness 0.25)
			(keepout
				(tracks allowed)
				(vias not_allowed)
				(pads allowed)
				(copperpour not_allowed)
				(footprints allowed)
			)
			(placement
				(enabled no)
				(sheetname "")
			)
			(fill
				(thermal_gap 0.5)
				(thermal_bridge_width 0.5)
				(island_removal_mode 0)
			)
			(polygon
				(pts
					(xy 102.3493 -149.3139) (xy 102.3493 -150.3045) (xy 101.8413 -150.3045) (xy 101.8413 -149.3139)
				)
			)
		)
		(zone
			(layer "F.Cu")
			(hatch none 0.5)
			(connect_pads
				(clearance 0)
			)
			(min_thickness 0.25)
			(keepout
				(tracks not_allowed)
				(vias allowed)
				(pads allowed)
				(copperpour not_allowed)
				(footprints allowed)
			)
			(placement
				(enabled no)
				(sheetname "")
			)
			(fill
				(thermal_gap 0.5)
				(thermal_bridge_width 0.5)
				(island_removal_mode 0)
			)
			(polygon
				(pts
					(xy 102.3493 -149.3139) (xy 102.3493 -150.3045) (xy 101.8413 -150.3045) (xy 101.8413 -149.3139)
				)
			)
		)
	)
	(footprint ""
		(layer "F.Cu")
		(at 173.736 -86.868 180)
		(property "Reference" "R4D8"
			(at 0 0 180)
			(layer "F.SilkS")
			(hide yes)
			(effects
				(font
					(size 1.27 1.27)
				)
			)
		)
		(property "Value" ""
			(at 0 0 180)
			(layer "F.Fab")
			(effects
				(font
					(size 1.27 1.27)
				)
			)
		)
		(duplicate_pad_numbers_are_jumpers no)
		(fp_poly
			(pts
				(xy -0.2794 -0.1016) (xy 0.2794 -0.1016) (xy 0.2794 0.9906) (xy -0.2794 0.9906)
			)
			(stroke
				(width 0)
				(type default)
			)
			(fill no)
			(layer "F.CrtYd")
		)
		(fp_line
			(start 0.2794 0.9906)
			(end 0.2794 -0.1016)
			(stroke
				(width 0.1)
				(type default)
			)
			(layer "F.Fab")
		)
		(fp_line
			(start 0.2794 -0.1016)
			(end -0.2794 -0.1016)
			(stroke
				(width 0.1)
				(type default)
			)
			(layer "F.Fab")
		)
		(fp_line
			(start -0.2794 0.9906)
			(end 0.2794 0.9906)
			(stroke
				(width 0.1)
				(type default)
			)
			(layer "F.Fab")
		)
		(fp_line
			(start -0.2794 -0.1016)
			(end -0.2794 0.9906)
			(stroke
				(width 0.1)
				(type default)
			)
			(layer "F.Fab")
		)
		(pad "1" smd rect
			(at 0 0 180)
			(size 0.508 0.508)
			(layers "F.Cu" "F.Mask" "F.Paste")
			(net "CLK_100M_CPU0_RC_REFCLK0_R_DP")
		)
		(pad "2" smd rect
			(at 0 0.889 180)
			(size 0.508 0.508)
			(layers "F.Cu" "F.Mask" "F.Paste")
			(net "CLK_100M_CPU0_RC_REFCLK0_DP")
		)
		(zone
			(layer "F.Cu")
			(hatch none 0.5)
			(connect_pads
				(clearance 0)
			)
			(min_thickness 0.25)
			(keepout
				(tracks not_allowed)
				(vias allowed)
				(pads allowed)
				(copperpour not_allowed)
				(footprints allowed)
			)
			(placement
				(enabled no)
				(sheetname "")
			)
			(fill
				(thermal_gap 0.5)
				(thermal_bridge_width 0.5)
				(island_removal_mode 0)
			)
			(polygon
				(pts
					(xy 173.99 -87.503) (xy 173.482 -87.503) (xy 173.482 -87.122) (xy 173.99 -87.122)
				)
			)
		)
		(zone
			(layer "F.Cu")
			(hatch none 0.5)
			(connect_pads
				(clearance 0)
			)
			(min_thickness 0.25)
			(keepout
				(tracks allowed)
				(vias not_allowed)
				(pads allowed)
				(copperpour not_allowed)
				(footprints allowed)
			)
			(placement
				(enabled no)
				(sheetname "")
			)
			(fill
				(thermal_gap 0.5)
				(thermal_bridge_width 0.5)
				(island_removal_mode 0)
			)
			(polygon
				(pts
					(xy 173.99 -87.122) (xy 173.482 -87.122) (xy 173.482 -87.503) (xy 173.99 -87.503)
				)
			)
		)
	)
)
